# T6G (Grand Teton) — schematic netlist excerpt (pin names and nets, part order shuffled) for the footprints in the layout excerpt that follows; sources: Cadence DE-HDL packaged netlist, KiCad conversion of 04192023_DAF0TMB3IC0_F0TG_MB_C_brd_V02_OCP.brd

C6702  Q_CAP_DIFFBUS  DIFF BUS_0.22UF 6.3V 20% X6S  pkg C0201  page 341 : \1\ = P5E_CPU1_P2_TX_BUF_C_DN<4> ; \2\ = P5E_CPU1_P2_TX_BUF_DN<4>

(kicad_pcb
	(version 20260206)
	(generator "pcbnew")
	(generator_version "10.0")
	(general
		(thickness 1.6)
		(legacy_teardrops no)
	)
	(paper "A4")
	(title_block
		(title "04192023_DAF0TMB3IC0_F0TG_MB_C_brd_V02_OCP.brd")
		(comment 1 "Grand Teton / footprints 3507-3507 of 8354")
	)
	(layers
		(0 "F.Cu" signal "TOP")
		(4 "In1.Cu" signal "GND")
		(6 "In2.Cu" signal "IN1")
		(8 "In3.Cu" signal "GND1")
		(10 "In4.Cu" signal "IN2")
		(12 "In5.Cu" signal "GND2")
		(14 "In6.Cu" signal "IN3")
		(16 "In7.Cu" signal "GND3")
		(18 "In8.Cu" signal "VCC")
		(20 "In9.Cu" signal "VCC1")
		(22 "In10.Cu" signal "GND4")
		(24 "In11.Cu" signal "IN4")
		(26 "In12.Cu" signal "GND5")
		(28 "In13.Cu" signal "IN5")
		(30 "In14.Cu" signal "GND6")
		(32 "In15.Cu" signal "IN6")
		(34 "In16.Cu" signal "GND7")
		(2 "B.Cu" signal "BOTTOM")
		(9 "F.Adhes" user "F.Adhesive")
		(11 "B.Adhes" user "B.Adhesive")
		(13 "F.Paste" user "Package Geometry/Pastemask Top")
		(15 "B.Paste" user "Package Geometry/Pastemask Bottom")
		(5 "F.SilkS" user "Ref Des/Silkscreen Top")
		(7 "B.SilkS" user "Ref Des/Silkscreen Bottom")
		(1 "F.Mask" user "Board Geometry/Soldermask Top")
		(3 "B.Mask" user "Board Geometry/Soldermask Bottom")
		(17 "Dwgs.User" user "User.Drawings")
		(19 "Cmts.User" user "User.Comments")
		(21 "Eco1.User" user "User.Eco1")
		(23 "Eco2.User" user "User.Eco2")
		(25 "Edge.Cuts" user "Board Geometry/Outline")
		(27 "Margin" user)
		(31 "F.CrtYd" user "Package Geometry/Place Bound Top")
		(29 "B.CrtYd" user "Package Geometry/Place Bound Bottom")
		(35 "F.Fab" user "Ref Des/Assembly Top")
		(33 "B.Fab" user "Ref Des/Assembly Bottom")
	)
	(footprint ""
		(layer "F.Cu")
		(at 127.121666 -408.517344 -90)
		(property "Reference" "C6702"
			(at 0 0 270)
			(layer "F.SilkS")
			(hide yes)
			(effects
				(font
					(size 1.27 1.27)
				)
			)
		)
		(property "Value" ""
			(at 0 0 270)
			(layer "F.Fab")
			(effects
				(font
					(size 1.27 1.27)
				)
			)
		)
		(duplicate_pad_numbers_are_jumpers no)
		(fp_line
			(start -0.299974 0.150114)
			(end -0.299974 -0.150114)
			(stroke
				(width 0.1)
				(type default)
			)
			(layer "F.Fab")
		)
		(fp_line
			(start 0.299974 0.150114)
			(end -0.299974 0.150114)
			(stroke
				(width 0.1)
				(type default)
			)
			(layer "F.Fab")
		)
		(fp_line
			(start -0.299974 -0.150114)
			(end 0.299974 -0.150114)
			(stroke
				(width 0.1)
				(type default)
			)
			(layer "F.Fab")
		)
		(fp_line
			(start 0.299974 -0.150114)
			(end 0.299974 0.150114)
			(stroke
				(width 0.1)
				(type default)
			)
			(layer "F.Fab")
		)
		(pad "1" smd rect
			(at -0.2667 0 270)
			(size 0.3048 0.381)
			(layers "F.Cu" "F.Mask" "F.Paste")
			(net "P5E_CPU1_P2_TX_BUF_C_DN<4>")
		)
		(pad "2" smd rect
			(at 0.2667 0 270)
			(size 0.3048 0.381)
			(layers "F.Cu" "F.Mask" "F.Paste")
			(net "P5E_CPU1_P2_TX_BUF_DN<4>")
		)
	)
)
